FILE_TYPE = CONNECTIVITY;
{Allegro Design Entry HDL 17.2-2016 S081 (4005846) 1/11/2022}
"PAGE_NUMBER" = 20;
0"NC";
1"M_K_CPU0_SA_DQ<31:0>";
2"M_K_CPU0_SB_DQ<31:0>";
3"M_K_CPU0_SA_CB<7:0>";
4"M_K_CPU0_SB_CB<7:0>";
5"M_K_CPU0_SA_DQS_DP<9:0>";
6"M_K_CPU0_SB_DQS_DP<9:0>";
7"M_K_CPU0_SA_CA<6:0>";
8"M_K_CPU0_SB_CA<6:0>";
9"M_K_CPU0_SA_DQS_DN<9:0>";
10"M_K_CPU0_SB_DQS_DN<9:0>";
11"M_K_CPU0_ALERT_N";
12"TP_M_K_CPU0_SA_TEST39K";
13"M_K_CPU0_ALERT_R_N";
14"M_K_CPU0_CLK_DP<0>";
15"M_K_CPU0_CLK_DN<0>";
16"M_K_CPU0_SA_CS_N<0>";
17"M_K_CPU0_SA_RSP<0>";
18"M_K_CPU0_SA_CS_N<1>";
19"M_K_CPU0_SA_PAR";
20"M_K_CPU0_SB_CS_N<0>";
21"M_K_CPU0_SB_CS_N<1>";
22"M_K_CPU0_SB_RSP<0>";
23"M_K_CPU0_SB_PAR";
24"M_K_CPU0_RESET_N";
25"M_K_CPU0_SA_CA<0>";
26"M_K_CPU0_SB_CA<6>";
27"M_K_CPU0_SA_CA<6>";
28"M_K_CPU0_SB_CA<5>";
29"M_K_CPU0_SA_CA<5>";
30"M_K_CPU0_SB_CA<4>";
31"M_K_CPU0_SA_CA<4>";
32"M_K_CPU0_SB_CA<3>";
33"M_K_CPU0_SB_DQS_DN<9>";
34"M_K_CPU0_SA_CA<3>";
35"M_K_CPU0_SB_CA<2>";
36"M_K_CPU0_SB_DQS_DN<8>";
37"M_K_CPU0_SA_CA<2>";
38"M_K_CPU0_SB_CA<1>";
39"M_K_CPU0_SA_CA<1>";
40"M_K_CPU0_SB_CA<0>";
41"M_K_CPU0_SB_DQS_DP<9>";
42"M_K_CPU0_SB_DQS_DN<5>";
43"M_K_CPU0_SB_DQS_DN<4>";
44"M_K_CPU0_SA_DQS_DN<9>";
45"M_K_CPU0_SB_DQS_DN<3>";
46"M_K_CPU0_SA_DQS_DN<8>";
47"M_K_CPU0_SB_DQS_DN<2>";
48"M_K_CPU0_SB_DQS_DN<1>";
49"M_K_CPU0_SB_DQS_DN<0>";
50"M_K_CPU0_SB_DQS_DN<7>";
51"M_K_CPU0_SB_DQS_DN<6>";
52"M_K_CPU0_SB_DQS_DP<8>";
53"M_K_CPU0_SB_DQS_DP<7>";
54"M_K_CPU0_SB_DQS_DP<6>";
55"M_K_CPU0_SB_DQS_DP<5>";
56"M_K_CPU0_SB_DQS_DP<4>";
57"M_K_CPU0_SB_DQS_DP<3>";
58"M_K_CPU0_SB_DQS_DP<1>";
59"M_K_CPU0_SB_DQS_DP<0>";
60"M_K_CPU0_SA_DQS_DP<9>";
61"M_K_CPU0_SB_DQS_DP<2>";
62"M_K_CPU0_SA_DQS_DN<7>";
63"M_K_CPU0_SA_DQS_DN<6>";
64"M_K_CPU0_SA_DQS_DN<5>";
65"M_K_CPU0_SA_DQS_DN<4>";
66"M_K_CPU0_SA_DQS_DN<3>";
67"M_K_CPU0_SA_DQS_DN<2>";
68"M_K_CPU0_SA_DQS_DN<1>";
69"M_K_CPU0_SA_DQS_DN<0>";
70"M_K_CPU0_SA_DQS_DP<7>";
71"M_K_CPU0_SA_DQS_DP<6>";
72"M_K_CPU0_SA_DQS_DP<5>";
73"M_K_CPU0_SA_DQS_DP<4>";
74"M_K_CPU0_SA_DQS_DP<8>";
75"M_K_CPU0_SA_DQS_DP<3>";
76"M_K_CPU0_SA_DQS_DP<2>";
77"M_K_CPU0_SA_DQS_DP<1>";
78"M_K_CPU0_SA_DQS_DP<0>";
79"M_K_CPU0_SB_CB<7>";
80"M_K_CPU0_SB_CB<6>";
81"M_K_CPU0_SB_CB<5>";
82"M_K_CPU0_SB_CB<4>";
83"M_K_CPU0_SB_CB<3>";
84"M_K_CPU0_SB_CB<2>";
85"M_K_CPU0_SA_CB<7>";
86"M_K_CPU0_SB_CB<1>";
87"M_K_CPU0_SB_CB<0>";
88"M_K_CPU0_SB_DQ<29>";
89"M_K_CPU0_SB_DQ<28>";
90"M_K_CPU0_SB_DQ<27>";
91"M_K_CPU0_SB_DQ<26>";
92"M_K_CPU0_SB_DQ<25>";
93"M_K_CPU0_SB_DQ<24>";
94"M_K_CPU0_SB_DQ<23>";
95"M_K_CPU0_SB_DQ<22>";
96"M_K_CPU0_SB_DQ<21>";
97"M_K_CPU0_SA_CB<6>";
98"M_K_CPU0_SB_DQ<20>";
99"M_K_CPU0_SB_DQ<31>";
100"M_K_CPU0_SA_CB<5>";
101"M_K_CPU0_SB_DQ<30>";
102"M_K_CPU0_SA_CB<4>";
103"M_K_CPU0_SA_CB<3>";
104"M_K_CPU0_SA_CB<2>";
105"M_K_CPU0_SA_CB<1>";
106"M_K_CPU0_SA_CB<0>";
107"M_K_CPU0_SB_DQ<9>";
108"M_K_CPU0_SB_DQ<18>";
109"M_K_CPU0_SB_DQ<8>";
110"M_K_CPU0_SB_DQ<17>";
111"M_K_CPU0_SB_DQ<7>";
112"M_K_CPU0_SB_DQ<16>";
113"M_K_CPU0_SB_DQ<6>";
114"M_K_CPU0_SB_DQ<15>";
115"M_K_CPU0_SB_DQ<5>";
116"M_K_CPU0_SB_DQ<14>";
117"M_K_CPU0_SB_DQ<4>";
118"M_K_CPU0_SB_DQ<13>";
119"M_K_CPU0_SB_DQ<3>";
120"M_K_CPU0_SB_DQ<12>";
121"M_K_CPU0_SB_DQ<2>";
122"M_K_CPU0_SB_DQ<11>";
123"M_K_CPU0_SB_DQ<10>";
124"M_K_CPU0_SB_DQ<19>";
125"M_K_CPU0_SA_DQ<19>";
126"M_K_CPU0_SA_DQ<18>";
127"M_K_CPU0_SA_DQ<29>";
128"M_K_CPU0_SA_DQ<17>";
129"M_K_CPU0_SA_DQ<28>";
130"M_K_CPU0_SA_DQ<16>";
131"M_K_CPU0_SA_DQ<27>";
132"M_K_CPU0_SB_DQ<1>";
133"M_K_CPU0_SA_DQ<26>";
134"M_K_CPU0_SB_DQ<0>";
135"M_K_CPU0_SA_DQ<25>";
136"M_K_CPU0_SA_DQ<24>";
137"M_K_CPU0_SA_DQ<23>";
138"M_K_CPU0_SA_DQ<22>";
139"M_K_CPU0_SA_DQ<21>";
140"M_K_CPU0_SA_DQ<20>";
141"M_K_CPU0_SA_DQ<31>";
142"M_K_CPU0_SA_DQ<30>";
143"M_K_CPU0_SA_DQ<9>";
144"M_K_CPU0_SA_DQ<8>";
145"M_K_CPU0_SA_DQ<7>";
146"M_K_CPU0_SA_DQ<6>";
147"M_K_CPU0_SA_DQ<5>";
148"M_K_CPU0_SA_DQ<4>";
149"M_K_CPU0_SA_DQ<3>";
150"M_K_CPU0_SA_DQ<2>";
151"M_K_CPU0_SA_DQ<1>";
152"M_K_CPU0_SA_DQ<15>";
153"M_K_CPU0_SA_DQ<0>";
154"M_K_CPU0_SA_DQ<14>";
155"M_K_CPU0_SA_DQ<13>";
156"M_K_CPU0_SA_DQ<12>";
157"M_K_CPU0_SA_DQ<11>";
158"M_K_CPU0_SA_DQ<10>";
%"GENOA_SP5"
"36","(-4425,3575)","0","pure_quanta","I159";
;
LOCATION"U25"
$SEC"36"
CDS_SEC"36"
PART_TYPE"SMLF"
MATERIAL"IO"
VALUE"SOCKET6096_13568-001"
PART_NUMBER"DGA^6000030"
NEEDS_NO_SIZE"TRUE"
CDS_LMAN_SYM_OUTLINE"-650,2525,650,-2525"
CDS_LIB"pure_quanta";
"TEST39K"
$PN"BF7"12;
"MKA0_CS_L0"
$PN"AU5"16;
"MKA_CA0"
$PN"AW5"25;
"MKA_DQS_H7"
$PN"AA7"70;
"MKB_DATA9"
$PN"CJ7"107;
"MKB_DATA18"
$PN"CR5"108;
"MKB_DATA29"
$PN"DE7"88;
"MKB_DQS_H1"
$PN"CK6"58;
"MKB_DQS_L5"
$PN"CE7"42;
"MKA_DATA9"
$PN"M7"143;
"MKA_DQS_H6"
$PN"R7"71;
"MKB1_RSP_L"
$PN"BR5"0;
"MKB_DATA8"
$PN"CH6"109;
"MKB_DATA17"
$PN"CR7"110;
"MKB_DATA28"
$PN"DD6"89;
"MKB_DQS_H0"
$PN"CD6"59;
"MKB_DQS_L4"
$PN"BW7"43;
"MKA_DATA8"
$PN"L5"144;
"MKA_DQS_H5"
$PN"J7"72;
"MKA_DQS_L9"
$PN"AM7"44;
"MKB0_RSP_L"
$PN"BP6"22;
"MKB_CHECK7"
$PN"BV7"79;
"MKB_DATA7"
$PN"CH7"111;
"MKB_DATA16"
$PN"CP6"112;
"MKB_DATA27"
$PN"DB7"90;
"MKB_DQS_L3"
$PN"DC5"45;
"MKA_DATA7"
$PN"L7"145;
"MKA_DQS_H4"
$PN"AL5"73;
"MKA_DQS_L8"
$PN"AF7"46;
"MKB_CHECK6"
$PN"BU5"80;
"MKB_DATA6"
$PN"CG5"113;
"MKB_DATA15"
$PN"CP7"114;
"MKB_DATA26"
$PN"DA5"91;
"MKB_DQS_L2"
$PN"CU5"47;
"MKB_PAR"
$PN"BL7"23;
"MKA_DATA6"
$PN"K6"146;
"MKA_DQS_H3"
$PN"AE5"75;
"MKA_DQS_L7"
$PN"Y7"62;
"MKA_PAR"
$PN"BC7"19;
"MKB_CHECK5"
$PN"BU7"81;
"MKB_DATA5"
$PN"CG7"115;
"MKB_DATA14"
$PN"CN5"116;
"MKB_DATA25"
$PN"DA7"92;
"MKB_DQS_L1"
$PN"CL5"48;
"MKA_DATA5"
$PN"K7"147;
"MKA_DATA19"
$PN"W7"125;
"MKA_DQS_H2"
$PN"W5"76;
"MKA_DQS_L6"
$PN"P7"63;
"MKB_CHECK4"
$PN"BT6"82;
"MKB_DATA4"
$PN"CF6"117;
"MKB_DATA13"
$PN"CN7"118;
"MKB_DATA24"
$PN"CY6"93;
"MKB_DQS_L0"
$PN"CE5"49;
"MKA_DATA4"
$PN"J5"148;
"MKA_DATA18"
$PN"V6"126;
"MKA_DATA29"
$PN"AH7"127;
"MKA_DQS_H1"
$PN"N5"77;
"MKA_DQS_L5"
$PN"H7"64;
"MKB_CHECK3"
$PN"CB7"83;
"MKB_DATA3"
$PN"CD7"119;
"MKB_DATA12"
$PN"CM6"120;
"MKB_DATA23"
$PN"CY7"94;
"MKA1_RSP_L"
$PN"BP7"0;
"MKA_DATA3"
$PN"G7"149;
"MKA_DATA17"
$PN"V7"128;
"MKA_DATA28"
$PN"AG5"129;
"MKA_DQS_H0"
$PN"G5"78;
"MKA_DQS_L4"
$PN"AM6"65;
"MKB_CHECK2"
$PN"CA5"84;
"MKB_DATA2"
$PN"CC5"121;
"MKB_DATA11"
$PN"CK7"122;
"MKB_DATA22"
$PN"CW5"95;
"MK_ALERT_L"
$PN"AT7"13;
"MKA0_RSP_L"
$PN"BN7"17;
"MKA_CHECK7"
$PN"AR7"85;
"MKA_DATA2"
$PN"F6"150;
"MKA_DATA16"
$PN"U5"130;
"MKA_DATA27"
$PN"AE7"131;
"MKA_DQS_L3"
$PN"AF6"66;
"MKB_CHECK1"
$PN"CA7"86;
"MKB_DATA1"
$PN"CC7"132;
"MKB_DATA10"
$PN"CJ5"123;
"MKB_DATA21"
$PN"CW7"96;
"MKA_CHECK6"
$PN"AP6"97;
"MKA_DATA1"
$PN"F7"151;
"MKA_DATA15"
$PN"U7"152;
"MKA_DATA26"
$PN"AD6"133;
"MKA_DQS_L2"
$PN"Y6"67;
"MKB1_CS_L1"
$PN"BM6"0;
"MKB_CHECK0"
$PN"BY6"87;
"MKB_DATA0"
$PN"CB6"134;
"MKB_DATA20"
$PN"CV6"98;
"MKB_DATA31"
$PN"DF7"99;
"MKB_DQS_H9"
$PN"BV6"41;
"MK1_CLK_L"
$PN"BG5"0;
"MKA_CHECK5"
$PN"AP7"100;
"MKA_DATA0"
$PN"E5"153;
"MKA_DATA14"
$PN"T6"154;
"MKA_DATA25"
$PN"AD7"135;
"MKA_DQS_L1"
$PN"P6"68;
"MKB0_CS_L1"
$PN"BN5"21;
"MKB1_CS_L0"
$PN"BL5"0;
"MKB_CA6"
$PN"BK6"26;
"MKB_DATA30"
$PN"DE5"101;
"MKB_DQS_H8"
$PN"DD7"52;
"MK0_CLK_L"
$PN"BD6"15;
"MKA_CA6"
$PN"BB7"27;
"MKA_CHECK4"
$PN"AN5"102;
"MKA_DATA13"
$PN"T7"155;
"MKA_DATA24"
$PN"AC5"136;
"MKA_DQS_L0"
$PN"H6"69;
"MKB0_CS_L0"
$PN"BM7"20;
"MKB_CA5"
$PN"BK7"28;
"MKB_DQS_H7"
$PN"CV7"53;
"MKA_CA5"
$PN"BB6"29;
"MKA_CHECK3"
$PN"AL7"103;
"MKA_DATA12"
$PN"R5"156;
"MKA_DATA23"
$PN"AC7"137;
"MKB_CA4"
$PN"BJ7"30;
"MKB_DQS_H6"
$PN"CM7"54;
"MK_RESET_L"
$PN"AU7"24;
"MKA_CA4"
$PN"BA5"31;
"MKA_CHECK2"
$PN"AK6"104;
"MKA_DATA11"
$PN"N7"157;
"MKA_DATA22"
$PN"AB6"138;
"MKB_CA3"
$PN"BJ5"32;
"MKB_DQS_H5"
$PN"CF7"55;
"MKB_DQS_L9"
$PN"BW5"33;
"MK1_CLK_H"
$PN"BF6"0;
"MKA_CA3"
$PN"BA7"34;
"MKA_CHECK1"
$PN"AK7"105;
"MKA_DATA10"
$PN"M6"158;
"MKA_DATA21"
$PN"AB7"139;
"MKB_CA2"
$PN"BH6"35;
"MKB_DQS_H4"
$PN"BY7"56;
"MKB_DQS_L8"
$PN"DC7"36;
"MK0_CLK_H"
$PN"BC5"14;
"MKA1_CS_L1"
$PN"AW7"0;
"MKA_CA2"
$PN"AY7"37;
"MKA_CHECK0"
$PN"AJ5"106;
"MKA_DATA20"
$PN"AA5"140;
"MKA_DATA31"
$PN"AJ7"141;
"MKA_DQS_H9"
$PN"AN7"60;
"MKB_CA1"
$PN"BH7"38;
"MKB_DQS_H3"
$PN"DB6"57;
"MKB_DQS_L7"
$PN"CU7"50;
"MKA0_CS_L1"
$PN"AV7"18;
"MKA1_CS_L0"
$PN"AV6"0;
"MKA_CA1"
$PN"AY6"39;
"MKA_DATA30"
$PN"AH6"142;
"MKA_DQS_H8"
$PN"AG7"74;
"MKB_CA0"
$PN"BG7"40;
"MKB_DATA19"
$PN"CT7"124;
"MKB_DQS_H2"
$PN"CT6"61;
"MKB_DQS_L6"
$PN"CL7"51;
%"TAP"
"1","(-3150,5950)","0","mstr_standard","I162";
;
CDS_LIB"mstr_standard"
BODY_TYPE"PLUMBING"
HDL_TAP"TRUE";
"B \NAC \NWC"1;
"S \NAC"
BN"0"153;
%"TAP"
"1","(-3150,5900)","0","mstr_standard","I163";
;
CDS_LIB"mstr_standard"
BODY_TYPE"PLUMBING"
HDL_TAP"TRUE";
"B \NAC \NWC"1;
"S \NAC"
BN"1"151;
%"TAP"
"1","(-3150,5850)","0","mstr_standard","I164";
;
CDS_LIB"mstr_standard"
BODY_TYPE"PLUMBING"
HDL_TAP"TRUE";
"B \NAC \NWC"1;
"S \NAC"
BN"2"150;
%"TAP"
"1","(-3150,5800)","0","mstr_standard","I165";
;
CDS_LIB"mstr_standard"
BODY_TYPE"PLUMBING"
HDL_TAP"TRUE";
"B \NAC \NWC"1;
"S \NAC"
BN"3"149;
%"TAP"
"1","(-3150,5700)","0","mstr_standard","I166";
;
CDS_LIB"mstr_standard"
BODY_TYPE"PLUMBING"
HDL_TAP"TRUE";
"B \NAC \NWC"1;
"S \NAC"
BN"5"147;
%"TAP"
"1","(-3150,5650)","0","mstr_standard","I167";
;
CDS_LIB"mstr_standard"
BODY_TYPE"PLUMBING"
HDL_TAP"TRUE";
"B \NAC \NWC"1;
"S \NAC"
BN"6"146;
%"TAP"
"1","(-3150,5750)","0","mstr_standard","I168";
;
CDS_LIB"mstr_standard"
BODY_TYPE"PLUMBING"
HDL_TAP"TRUE";
"B \NAC \NWC"1;
"S \NAC"
BN"4"148;
%"TAP"
"1","(-3150,5600)","0","mstr_standard","I169";
;
CDS_LIB"mstr_standard"
BODY_TYPE"PLUMBING"
HDL_TAP"TRUE";
"B \NAC \NWC"1;
"S \NAC"
BN"7"145;
%"TAP"
"1","(-3150,5400)","0","mstr_standard","I170";
;
CDS_LIB"mstr_standard"
BODY_TYPE"PLUMBING"
HDL_TAP"TRUE";
"B \NAC \NWC"1;
"S \NAC"
BN"10"158;
%"TAP"
"1","(-3150,5450)","0","mstr_standard","I171";
;
CDS_LIB"mstr_standard"
BODY_TYPE"PLUMBING"
HDL_TAP"TRUE";
"B \NAC \NWC"1;
"S \NAC"
BN"9"143;
%"TAP"
"1","(-3150,5500)","0","mstr_standard","I172";
;
CDS_LIB"mstr_standard"
BODY_TYPE"PLUMBING"
HDL_TAP"TRUE";
"B \NAC \NWC"1;
"S \NAC"
BN"8"144;
%"TAP"
"1","(-3150,5250)","0","mstr_standard","I173";
;
CDS_LIB"mstr_standard"
BODY_TYPE"PLUMBING"
HDL_TAP"TRUE";
"B \NAC \NWC"1;
"S \NAC"
BN"13"155;
%"TAP"
"1","(-3150,5350)","0","mstr_standard","I174";
;
CDS_LIB"mstr_standard"
BODY_TYPE"PLUMBING"
HDL_TAP"TRUE";
"B \NAC \NWC"1;
"S \NAC"
BN"11"157;
%"TAP"
"1","(-3150,5300)","0","mstr_standard","I175";
;
CDS_LIB"mstr_standard"
BODY_TYPE"PLUMBING"
HDL_TAP"TRUE";
"B \NAC \NWC"1;
"S \NAC"
BN"12"156;
%"TAP"
"1","(-3150,5150)","0","mstr_standard","I176";
;
CDS_LIB"mstr_standard"
BODY_TYPE"PLUMBING"
HDL_TAP"TRUE";
"B \NAC \NWC"1;
"S \NAC"
BN"15"152;
%"TAP"
"1","(-3150,5200)","0","mstr_standard","I177";
;
CDS_LIB"mstr_standard"
BODY_TYPE"PLUMBING"
HDL_TAP"TRUE";
"B \NAC \NWC"1;
"S \NAC"
BN"14"154;
%"TAP"
"1","(-3150,5000)","0","mstr_standard","I178";
;
CDS_LIB"mstr_standard"
BODY_TYPE"PLUMBING"
HDL_TAP"TRUE";
"B \NAC \NWC"1;
"S \NAC"
BN"17"128;
%"TAP"
"1","(-3150,5050)","0","mstr_standard","I179";
;
CDS_LIB"mstr_standard"
BODY_TYPE"PLUMBING"
HDL_TAP"TRUE";
"B \NAC \NWC"1;
"S \NAC"
BN"16"130;
%"TAP"
"1","(-3150,4900)","0","mstr_standard","I180";
;
CDS_LIB"mstr_standard"
BODY_TYPE"PLUMBING"
HDL_TAP"TRUE";
"B \NAC \NWC"1;
"S \NAC"
BN"19"125;
%"TAP"
"1","(-3150,4950)","0","mstr_standard","I181";
;
CDS_LIB"mstr_standard"
BODY_TYPE"PLUMBING"
HDL_TAP"TRUE";
"B \NAC \NWC"1;
"S \NAC"
BN"18"126;
%"TAP"
"1","(-3150,4850)","0","mstr_standard","I182";
;
CDS_LIB"mstr_standard"
BODY_TYPE"PLUMBING"
HDL_TAP"TRUE";
"B \NAC \NWC"1;
"S \NAC"
BN"20"140;
%"TAP"
"1","(-3150,4750)","0","mstr_standard","I183";
;
CDS_LIB"mstr_standard"
BODY_TYPE"PLUMBING"
HDL_TAP"TRUE";
"B \NAC \NWC"1;
"S \NAC"
BN"22"138;
%"TAP"
"1","(-3150,4800)","0","mstr_standard","I184";
;
CDS_LIB"mstr_standard"
BODY_TYPE"PLUMBING"
HDL_TAP"TRUE";
"B \NAC \NWC"1;
"S \NAC"
BN"21"139;
%"TAP"
"1","(-3150,4700)","0","mstr_standard","I185";
;
CDS_LIB"mstr_standard"
BODY_TYPE"PLUMBING"
HDL_TAP"TRUE";
"B \NAC \NWC"1;
"S \NAC"
BN"23"137;
%"TAP"
"1","(-3150,4550)","0","mstr_standard","I186";
;
CDS_LIB"mstr_standard"
BODY_TYPE"PLUMBING"
HDL_TAP"TRUE";
"B \NAC \NWC"1;
"S \NAC"
BN"25"135;
%"TAP"
"1","(-3150,4600)","0","mstr_standard","I187";
;
CDS_LIB"mstr_standard"
BODY_TYPE"PLUMBING"
HDL_TAP"TRUE";
"B \NAC \NWC"1;
"S \NAC"
BN"24"136;
%"TAP"
"1","(-3150,4500)","0","mstr_standard","I188";
;
CDS_LIB"mstr_standard"
BODY_TYPE"PLUMBING"
HDL_TAP"TRUE";
"B \NAC \NWC"1;
"S \NAC"
BN"26"133;
%"TAP"
"1","(-3150,4400)","0","mstr_standard","I189";
;
CDS_LIB"mstr_standard"
BODY_TYPE"PLUMBING"
HDL_TAP"TRUE";
"B \NAC \NWC"1;
"S \NAC"
BN"28"129;
%"TAP"
"1","(-3150,4450)","0","mstr_standard","I190";
;
CDS_LIB"mstr_standard"
BODY_TYPE"PLUMBING"
HDL_TAP"TRUE";
"B \NAC \NWC"1;
"S \NAC"
BN"27"131;
%"TAP"
"1","(-3150,4350)","0","mstr_standard","I191";
;
CDS_LIB"mstr_standard"
BODY_TYPE"PLUMBING"
HDL_TAP"TRUE";
"B \NAC \NWC"1;
"S \NAC"
BN"29"127;
%"TAP"
"1","(-3150,4250)","0","mstr_standard","I192";
;
CDS_LIB"mstr_standard"
BODY_TYPE"PLUMBING"
HDL_TAP"TRUE";
"B \NAC \NWC"1;
"S \NAC"
BN"31"141;
%"TAP"
"1","(-3150,4300)","0","mstr_standard","I193";
;
CDS_LIB"mstr_standard"
BODY_TYPE"PLUMBING"
HDL_TAP"TRUE";
"B \NAC \NWC"1;
"S \NAC"
BN"30"142;
%"TAP"
"1","(-3150,4100)","0","mstr_standard","I194";
;
CDS_LIB"mstr_standard"
BODY_TYPE"PLUMBING"
HDL_TAP"TRUE";
"B \NAC \NWC"2;
"S \NAC"
BN"1"132;
%"TAP"
"1","(-3150,4150)","0","mstr_standard","I195";
;
CDS_LIB"mstr_standard"
BODY_TYPE"PLUMBING"
HDL_TAP"TRUE";
"B \NAC \NWC"2;
"S \NAC"
BN"0"134;
%"TAP"
"1","(-3150,4050)","0","mstr_standard","I197";
;
CDS_LIB"mstr_standard"
BODY_TYPE"PLUMBING"
HDL_TAP"TRUE";
"B \NAC \NWC"2;
"S \NAC"
BN"2"121;
%"TAP"
"1","(-3150,4000)","0","mstr_standard","I198";
;
CDS_LIB"mstr_standard"
BODY_TYPE"PLUMBING"
HDL_TAP"TRUE";
"B \NAC \NWC"2;
"S \NAC"
BN"3"119;
%"TAP"
"1","(-3150,3900)","0","mstr_standard","I199";
;
CDS_LIB"mstr_standard"
BODY_TYPE"PLUMBING"
HDL_TAP"TRUE";
"B \NAC \NWC"2;
"S \NAC"
BN"5"115;
%"TAP"
"1","(-3150,3850)","0","mstr_standard","I200";
;
CDS_LIB"mstr_standard"
BODY_TYPE"PLUMBING"
HDL_TAP"TRUE";
"B \NAC \NWC"2;
"S \NAC"
BN"6"113;
%"TAP"
"1","(-3150,3950)","0","mstr_standard","I201";
;
CDS_LIB"mstr_standard"
BODY_TYPE"PLUMBING"
HDL_TAP"TRUE";
"B \NAC \NWC"2;
"S \NAC"
BN"4"117;
%"TAP"
"1","(-3150,3800)","0","mstr_standard","I202";
;
CDS_LIB"mstr_standard"
BODY_TYPE"PLUMBING"
HDL_TAP"TRUE";
"B \NAC \NWC"2;
"S \NAC"
BN"7"111;
%"TAP"
"1","(-3150,3600)","0","mstr_standard","I203";
;
CDS_LIB"mstr_standard"
BODY_TYPE"PLUMBING"
HDL_TAP"TRUE";
"B \NAC \NWC"2;
"S \NAC"
BN"10"123;
%"TAP"
"1","(-3150,3650)","0","mstr_standard","I204";
;
CDS_LIB"mstr_standard"
BODY_TYPE"PLUMBING"
HDL_TAP"TRUE";
"B \NAC \NWC"2;
"S \NAC"
BN"9"107;
%"TAP"
"1","(-3150,3700)","0","mstr_standard","I205";
;
CDS_LIB"mstr_standard"
BODY_TYPE"PLUMBING"
HDL_TAP"TRUE";
"B \NAC \NWC"2;
"S \NAC"
BN"8"109;
%"TAP"
"1","(-3150,3500)","0","mstr_standard","I206";
;
CDS_LIB"mstr_standard"
BODY_TYPE"PLUMBING"
HDL_TAP"TRUE";
"B \NAC \NWC"2;
"S \NAC"
BN"12"120;
%"TAP"
"1","(-3150,3550)","0","mstr_standard","I207";
;
CDS_LIB"mstr_standard"
BODY_TYPE"PLUMBING"
HDL_TAP"TRUE";
"B \NAC \NWC"2;
"S \NAC"
BN"11"122;
%"TAP"
"1","(-3150,3400)","0","mstr_standard","I208";
;
CDS_LIB"mstr_standard"
BODY_TYPE"PLUMBING"
HDL_TAP"TRUE";
"B \NAC \NWC"2;
"S \NAC"
BN"14"116;
%"TAP"
"1","(-3150,3350)","0","mstr_standard","I209";
;
CDS_LIB"mstr_standard"
BODY_TYPE"PLUMBING"
HDL_TAP"TRUE";
"B \NAC \NWC"2;
"S \NAC"
BN"15"114;
%"TAP"
"1","(-3150,3450)","0","mstr_standard","I210";
;
CDS_LIB"mstr_standard"
BODY_TYPE"PLUMBING"
HDL_TAP"TRUE";
"B \NAC \NWC"2;
"S \NAC"
BN"13"118;
%"TAP"
"1","(-3150,3250)","0","mstr_standard","I211";
;
CDS_LIB"mstr_standard"
BODY_TYPE"PLUMBING"
HDL_TAP"TRUE";
"B \NAC \NWC"2;
"S \NAC"
BN"16"112;
%"TAP"
"1","(-3150,3200)","0","mstr_standard","I212";
;
CDS_LIB"mstr_standard"
BODY_TYPE"PLUMBING"
HDL_TAP"TRUE";
"B \NAC \NWC"2;
"S \NAC"
BN"17"110;
%"TAP"
"1","(-3150,3100)","0","mstr_standard","I213";
;
CDS_LIB"mstr_standard"
BODY_TYPE"PLUMBING"
HDL_TAP"TRUE";
"B \NAC \NWC"2;
"S \NAC"
BN"19"124;
%"TAP"
"1","(-3150,3150)","0","mstr_standard","I214";
;
CDS_LIB"mstr_standard"
BODY_TYPE"PLUMBING"
HDL_TAP"TRUE";
"B \NAC \NWC"2;
"S \NAC"
BN"18"108;
%"TAP"
"1","(-3150,3000)","0","mstr_standard","I215";
;
CDS_LIB"mstr_standard"
BODY_TYPE"PLUMBING"
HDL_TAP"TRUE";
"B \NAC \NWC"2;
"S \NAC"
BN"21"96;
%"TAP"
"1","(-3150,3050)","0","mstr_standard","I216";
;
CDS_LIB"mstr_standard"
BODY_TYPE"PLUMBING"
HDL_TAP"TRUE";
"B \NAC \NWC"2;
"S \NAC"
BN"20"98;
%"TAP"
"1","(-3150,2950)","0","mstr_standard","I217";
;
CDS_LIB"mstr_standard"
BODY_TYPE"PLUMBING"
HDL_TAP"TRUE";
"B \NAC \NWC"2;
"S \NAC"
BN"22"95;
%"TAP"
"1","(-3150,2900)","0","mstr_standard","I218";
;
CDS_LIB"mstr_standard"
BODY_TYPE"PLUMBING"
HDL_TAP"TRUE";
"B \NAC \NWC"2;
"S \NAC"
BN"23"94;
%"TAP"
"1","(-3150,2800)","0","mstr_standard","I219";
;
CDS_LIB"mstr_standard"
BODY_TYPE"PLUMBING"
HDL_TAP"TRUE";
"B \NAC \NWC"2;
"S \NAC"
BN"24"93;
%"TAP"
"1","(-3150,2750)","0","mstr_standard","I220";
;
CDS_LIB"mstr_standard"
BODY_TYPE"PLUMBING"
HDL_TAP"TRUE";
"B \NAC \NWC"2;
"S \NAC"
BN"25"92;
%"TAP"
"1","(-3150,2700)","0","mstr_standard","I221";
;
CDS_LIB"mstr_standard"
BODY_TYPE"PLUMBING"
HDL_TAP"TRUE";
"B \NAC \NWC"2;
"S \NAC"
BN"26"91;
%"TAP"
"1","(-3150,2600)","0","mstr_standard","I222";
;
CDS_LIB"mstr_standard"
BODY_TYPE"PLUMBING"
HDL_TAP"TRUE";
"B \NAC \NWC"2;
"S \NAC"
BN"28"89;
%"TAP"
"1","(-3150,2650)","0","mstr_standard","I223";
;
CDS_LIB"mstr_standard"
BODY_TYPE"PLUMBING"
HDL_TAP"TRUE";
"B \NAC \NWC"2;
"S \NAC"
BN"27"90;
%"TAP"
"1","(-3150,2550)","0","mstr_standard","I224";
;
CDS_LIB"mstr_standard"
BODY_TYPE"PLUMBING"
HDL_TAP"TRUE";
"B \NAC \NWC"2;
"S \NAC"
BN"29"88;
%"TAP"
"1","(-3150,2500)","0","mstr_standard","I225";
;
CDS_LIB"mstr_standard"
BODY_TYPE"PLUMBING"
HDL_TAP"TRUE";
"B \NAC \NWC"2;
"S \NAC"
BN"30"101;
%"TAP"
"1","(-3150,2450)","0","mstr_standard","I226";
;
CDS_LIB"mstr_standard"
BODY_TYPE"PLUMBING"
HDL_TAP"TRUE";
"B \NAC \NWC"2;
"S \NAC"
BN"31"99;
%"TAP"
"1","(-3150,2350)","0","mstr_standard","I227";
;
CDS_LIB"mstr_standard"
BODY_TYPE"PLUMBING"
HDL_TAP"TRUE";
"B \NAC \NWC"3;
"S \NAC"
BN"0"106;
%"TAP"
"1","(-3150,2300)","0","mstr_standard","I228";
;
CDS_LIB"mstr_standard"
BODY_TYPE"PLUMBING"
HDL_TAP"TRUE";
"B \NAC \NWC"3;
"S \NAC"
BN"1"105;
%"TAP"
"1","(-3150,2250)","0","mstr_standard","I229";
;
CDS_LIB"mstr_standard"
BODY_TYPE"PLUMBING"
HDL_TAP"TRUE";
"B \NAC \NWC"3;
"S \NAC"
BN"2"104;
%"TAP"
"1","(-3150,2200)","0","mstr_standard","I230";
;
CDS_LIB"mstr_standard"
BODY_TYPE"PLUMBING"
HDL_TAP"TRUE";
"B \NAC \NWC"3;
"S \NAC"
BN"3"103;
%"TAP"
"1","(-3150,2050)","0","mstr_standard","I231";
;
CDS_LIB"mstr_standard"
BODY_TYPE"PLUMBING"
HDL_TAP"TRUE";
"B \NAC \NWC"3;
"S \NAC"
BN"6"97;
%"TAP"
"1","(-3150,2150)","0","mstr_standard","I232";
;
CDS_LIB"mstr_standard"
BODY_TYPE"PLUMBING"
HDL_TAP"TRUE";
"B \NAC \NWC"3;
"S \NAC"
BN"4"102;
%"TAP"
"1","(-3150,2100)","0","mstr_standard","I233";
;
CDS_LIB"mstr_standard"
BODY_TYPE"PLUMBING"
HDL_TAP"TRUE";
"B \NAC \NWC"3;
"S \NAC"
BN"5"100;
%"TAP"
"1","(-3150,2000)","0","mstr_standard","I235";
;
CDS_LIB"mstr_standard"
BODY_TYPE"PLUMBING"
HDL_TAP"TRUE";
"B \NAC \NWC"3;
"S \NAC"
BN"7"85;
%"TAP"
"1","(-3150,1800)","0","mstr_standard","I236";
;
CDS_LIB"mstr_standard"
BODY_TYPE"PLUMBING"
HDL_TAP"TRUE";
"B \NAC \NWC"4;
"S \NAC"
BN"2"84;
%"TAP"
"1","(-3150,1850)","0","mstr_standard","I237";
;
CDS_LIB"mstr_standard"
BODY_TYPE"PLUMBING"
HDL_TAP"TRUE";
"B \NAC \NWC"4;
"S \NAC"
BN"1"86;
%"TAP"
"1","(-3150,1900)","0","mstr_standard","I238";
;
CDS_LIB"mstr_standard"
BODY_TYPE"PLUMBING"
HDL_TAP"TRUE";
"B \NAC \NWC"4;
"S \NAC"
BN"0"87;
%"TAP"
"1","(-3150,1750)","0","mstr_standard","I239";
;
CDS_LIB"mstr_standard"
BODY_TYPE"PLUMBING"
HDL_TAP"TRUE";
"B \NAC \NWC"4;
"S \NAC"
BN"3"83;
%"TAP"
"1","(-3150,1700)","0","mstr_standard","I240";
;
CDS_LIB"mstr_standard"
BODY_TYPE"PLUMBING"
HDL_TAP"TRUE";
"B \NAC \NWC"4;
"S \NAC"
BN"4"82;
%"TAP"
"1","(-3150,1550)","0","mstr_standard","I241";
;
CDS_LIB"mstr_standard"
BODY_TYPE"PLUMBING"
HDL_TAP"TRUE";
"B \NAC \NWC"4;
"S \NAC"
BN"7"79;
%"TAP"
"1","(-3150,1600)","0","mstr_standard","I242";
;
CDS_LIB"mstr_standard"
BODY_TYPE"PLUMBING"
HDL_TAP"TRUE";
"B \NAC \NWC"4;
"S \NAC"
BN"6"80;
%"TAP"
"1","(-3150,1650)","0","mstr_standard","I243";
;
CDS_LIB"mstr_standard"
BODY_TYPE"PLUMBING"
HDL_TAP"TRUE";
"B \NAC \NWC"4;
"S \NAC"
BN"5"81;
%"TAP"
"1","(-5575,5950)","2","mstr_standard","I244";
;
CDS_LIB"mstr_standard"
BODY_TYPE"PLUMBING"
HDL_TAP"TRUE";
"B \NAC \NWC"5;
"S \NAC"
BN"0"78;
%"TAP"
"1","(-5575,5850)","2","mstr_standard","I245";
;
CDS_LIB"mstr_standard"
BODY_TYPE"PLUMBING"
HDL_TAP"TRUE";
"B \NAC \NWC"5;
"S \NAC"
BN"1"77;
%"TAP"
"1","(-5575,5750)","2","mstr_standard","I246";
;
CDS_LIB"mstr_standard"
BODY_TYPE"PLUMBING"
HDL_TAP"TRUE";
"B \NAC \NWC"5;
"S \NAC"
BN"2"76;
%"TAP"
"1","(-5575,5650)","2","mstr_standard","I247";
;
CDS_LIB"mstr_standard"
BODY_TYPE"PLUMBING"
HDL_TAP"TRUE";
"B \NAC \NWC"5;
"S \NAC"
BN"3"75;
%"TAP"
"1","(-5575,5450)","2","mstr_standard","I248";
;
CDS_LIB"mstr_standard"
BODY_TYPE"PLUMBING"
HDL_TAP"TRUE";
"B \NAC \NWC"5;
"S \NAC"
BN"5"72;
%"TAP"
"1","(-5575,5550)","2","mstr_standard","I249";
;
CDS_LIB"mstr_standard"
BODY_TYPE"PLUMBING"
HDL_TAP"TRUE";
"B \NAC \NWC"5;
"S \NAC"
BN"4"73;
%"TAP"
"1","(-5575,5250)","2","mstr_standard","I250";
;
CDS_LIB"mstr_standard"
BODY_TYPE"PLUMBING"
HDL_TAP"TRUE";
"B \NAC \NWC"5;
"S \NAC"
BN"7"70;
%"TAP"
"1","(-5575,5350)","2","mstr_standard","I251";
;
CDS_LIB"mstr_standard"
BODY_TYPE"PLUMBING"
HDL_TAP"TRUE";
"B \NAC \NWC"5;
"S \NAC"
BN"6"71;
%"TAP"
"1","(-5575,5150)","2","mstr_standard","I252";
;
CDS_LIB"mstr_standard"
BODY_TYPE"PLUMBING"
HDL_TAP"TRUE";
"B \NAC \NWC"5;
"S \NAC"
BN"8"74;
%"TAP"
"1","(-5775,5900)","2","mstr_standard","I253";
;
CDS_LIB"mstr_standard"
BODY_TYPE"PLUMBING"
HDL_TAP"TRUE";
"B \NAC \NWC"9;
"S \NAC"
BN"0"69;
%"TAP"
"1","(-5775,5800)","2","mstr_standard","I254";
;
CDS_LIB"mstr_standard"
BODY_TYPE"PLUMBING"
HDL_TAP"TRUE";
"B \NAC \NWC"9;
"S \NAC"
BN"1"68;
%"TAP"
"1","(-5775,5700)","2","mstr_standard","I255";
;
CDS_LIB"mstr_standard"
BODY_TYPE"PLUMBING"
HDL_TAP"TRUE";
"B \NAC \NWC"9;
"S \NAC"
BN"2"67;
%"TAP"
"1","(-5775,5600)","2","mstr_standard","I256";
;
CDS_LIB"mstr_standard"
BODY_TYPE"PLUMBING"
HDL_TAP"TRUE";
"B \NAC \NWC"9;
"S \NAC"
BN"3"66;
%"TAP"
"1","(-5775,5400)","2","mstr_standard","I257";
;
CDS_LIB"mstr_standard"
BODY_TYPE"PLUMBING"
HDL_TAP"TRUE";
"B \NAC \NWC"9;
"S \NAC"
BN"5"64;
%"TAP"
"1","(-5775,5500)","2","mstr_standard","I258";
;
CDS_LIB"mstr_standard"
BODY_TYPE"PLUMBING"
HDL_TAP"TRUE";
"B \NAC \NWC"9;
"S \NAC"
BN"4"65;
%"TAP"
"1","(-5775,5300)","2","mstr_standard","I259";
;
CDS_LIB"mstr_standard"
BODY_TYPE"PLUMBING"
HDL_TAP"TRUE";
"B \NAC \NWC"9;
"S \NAC"
BN"6"63;
%"TAP"
"1","(-5775,5200)","2","mstr_standard","I260";
;
CDS_LIB"mstr_standard"
BODY_TYPE"PLUMBING"
HDL_TAP"TRUE";
"B \NAC \NWC"9;
"S \NAC"
BN"7"62;
%"TAP"
"1","(-5575,4900)","2","mstr_standard","I261";
;
CDS_LIB"mstr_standard"
BODY_TYPE"PLUMBING"
HDL_TAP"TRUE";
"B \NAC \NWC"6;
"S \NAC"
BN"0"59;
%"TAP"
"1","(-5575,5050)","2","mstr_standard","I262";
;
CDS_LIB"mstr_standard"
BODY_TYPE"PLUMBING"
HDL_TAP"TRUE";
"B \NAC \NWC"5;
"S \NAC"
BN"9"60;
%"TAP"
"1","(-5575,4800)","2","mstr_standard","I263";
;
CDS_LIB"mstr_standard"
BODY_TYPE"PLUMBING"
HDL_TAP"TRUE";
"B \NAC \NWC"6;
"S \NAC"
BN"1"58;
%"TAP"
"1","(-5575,4700)","2","mstr_standard","I264";
;
CDS_LIB"mstr_standard"
BODY_TYPE"PLUMBING"
HDL_TAP"TRUE";
"B \NAC \NWC"6;
"S \NAC"
BN"2"61;
%"TAP"
"1","(-5575,4600)","2","mstr_standard","I265";
;
CDS_LIB"mstr_standard"
BODY_TYPE"PLUMBING"
HDL_TAP"TRUE";
"B \NAC \NWC"6;
"S \NAC"
BN"3"57;
%"TAP"
"1","(-5575,4400)","2","mstr_standard","I266";
;
CDS_LIB"mstr_standard"
BODY_TYPE"PLUMBING"
HDL_TAP"TRUE";
"B \NAC \NWC"6;
"S \NAC"
BN"5"55;
%"TAP"
"1","(-5575,4500)","2","mstr_standard","I267";
;
CDS_LIB"mstr_standard"
BODY_TYPE"PLUMBING"
HDL_TAP"TRUE";
"B \NAC \NWC"6;
"S \NAC"
BN"4"56;
%"TAP"
"1","(-5575,4200)","2","mstr_standard","I268";
;
CDS_LIB"mstr_standard"
BODY_TYPE"PLUMBING"
HDL_TAP"TRUE";
"B \NAC \NWC"6;
"S \NAC"
BN"7"53;
%"TAP"
"1","(-5575,4300)","2","mstr_standard","I269";
;
CDS_LIB"mstr_standard"
BODY_TYPE"PLUMBING"
HDL_TAP"TRUE";
"B \NAC \NWC"6;
"S \NAC"
BN"6"54;
%"TAP"
"1","(-5575,4100)","2","mstr_standard","I270";
;
CDS_LIB"mstr_standard"
BODY_TYPE"PLUMBING"
HDL_TAP"TRUE";
"B \NAC \NWC"6;
"S \NAC"
BN"8"52;
%"TAP"
"1","(-5775,5100)","2","mstr_standard","I271";
;
CDS_LIB"mstr_standard"
BODY_TYPE"PLUMBING"
HDL_TAP"TRUE";
"B \NAC \NWC"9;
"S \NAC"
BN"8"46;
%"TAP"
"1","(-5775,5000)","2","mstr_standard","I272";
;
CDS_LIB"mstr_standard"
BODY_TYPE"PLUMBING"
HDL_TAP"TRUE";
"B \NAC \NWC"9;
"S \NAC"
BN"9"44;
%"TAP"
"1","(-5775,4850)","2","mstr_standard","I273";
;
CDS_LIB"mstr_standard"
BODY_TYPE"PLUMBING"
HDL_TAP"TRUE";
"B \NAC \NWC"10;
"S \NAC"
BN"0"49;
%"TAP"
"1","(-5775,4750)","2","mstr_standard","I274";
;
CDS_LIB"mstr_standard"
BODY_TYPE"PLUMBING"
HDL_TAP"TRUE";
"B \NAC \NWC"10;
"S \NAC"
BN"1"48;
%"TAP"
"1","(-5775,4650)","2","mstr_standard","I275";
;
CDS_LIB"mstr_standard"
BODY_TYPE"PLUMBING"
HDL_TAP"TRUE";
"B \NAC \NWC"10;
"S \NAC"
BN"2"47;
%"TAP"
"1","(-5775,4550)","2","mstr_standard","I276";
;
CDS_LIB"mstr_standard"
BODY_TYPE"PLUMBING"
HDL_TAP"TRUE";
"B \NAC \NWC"10;
"S \NAC"
BN"3"45;
%"TAP"
"1","(-5775,4450)","2","mstr_standard","I277";
;
CDS_LIB"mstr_standard"
BODY_TYPE"PLUMBING"
HDL_TAP"TRUE";
"B \NAC \NWC"10;
"S \NAC"
BN"4"43;
%"TAP"
"1","(-5775,4250)","2","mstr_standard","I278";
;
CDS_LIB"mstr_standard"
BODY_TYPE"PLUMBING"
HDL_TAP"TRUE";
"B \NAC \NWC"10;
"S \NAC"
BN"6"51;
%"TAP"
"1","(-5775,4350)","2","mstr_standard","I279";
;
CDS_LIB"mstr_standard"
BODY_TYPE"PLUMBING"
HDL_TAP"TRUE";
"B \NAC \NWC"10;
"S \NAC"
BN"5"42;
%"TAP"
"1","(-5775,4150)","2","mstr_standard","I280";
;
CDS_LIB"mstr_standard"
BODY_TYPE"PLUMBING"
HDL_TAP"TRUE";
"B \NAC \NWC"10;
"S \NAC"
BN"7"50;
%"TAP"
"1","(-5575,4000)","2","mstr_standard","I285";
;
CDS_LIB"mstr_standard"
BODY_TYPE"PLUMBING"
HDL_TAP"TRUE";
"B \NAC \NWC"6;
"S \NAC"
BN"9"41;
%"TAP"
"1","(-5775,4050)","2","mstr_standard","I286";
;
CDS_LIB"mstr_standard"
BODY_TYPE"PLUMBING"
HDL_TAP"TRUE";
"B \NAC \NWC"10;
"S \NAC"
BN"8"36;
%"TAP"
"1","(-5775,3950)","2","mstr_standard","I287";
;
CDS_LIB"mstr_standard"
BODY_TYPE"PLUMBING"
HDL_TAP"TRUE";
"B \NAC \NWC"10;
"S \NAC"
BN"9"33;
%"TAP"
"1","(-5775,3800)","2","mstr_standard","I288";
;
CDS_LIB"mstr_standard"
BODY_TYPE"PLUMBING"
HDL_TAP"TRUE";
"B \NAC \NWC"7;
"S \NAC"
BN"0"25;
%"TAP"
"1","(-5775,3750)","2","mstr_standard","I289";
;
CDS_LIB"mstr_standard"
BODY_TYPE"PLUMBING"
HDL_TAP"TRUE";
"B \NAC \NWC"7;
"S \NAC"
BN"1"39;
%"TAP"
"1","(-5775,3700)","2","mstr_standard","I290";
;
CDS_LIB"mstr_standard"
BODY_TYPE"PLUMBING"
HDL_TAP"TRUE";
"B \NAC \NWC"7;
"S \NAC"
BN"2"37;
%"TAP"
"1","(-5775,3650)","2","mstr_standard","I291";
;
CDS_LIB"mstr_standard"
BODY_TYPE"PLUMBING"
HDL_TAP"TRUE";
"B \NAC \NWC"7;
"S \NAC"
BN"3"34;
%"TAP"
"1","(-5775,3600)","2","mstr_standard","I292";
;
CDS_LIB"mstr_standard"
BODY_TYPE"PLUMBING"
HDL_TAP"TRUE";
"B \NAC \NWC"7;
"S \NAC"
BN"4"31;
%"TAP"
"1","(-5775,3500)","2","mstr_standard","I293";
;
CDS_LIB"mstr_standard"
BODY_TYPE"PLUMBING"
HDL_TAP"TRUE";
"B \NAC \NWC"7;
"S \NAC"
BN"6"27;
%"TAP"
"1","(-5775,3550)","2","mstr_standard","I294";
;
CDS_LIB"mstr_standard"
BODY_TYPE"PLUMBING"
HDL_TAP"TRUE";
"B \NAC \NWC"7;
"S \NAC"
BN"5"29;
%"TAP"
"1","(-5775,3400)","2","mstr_standard","I295";
;
CDS_LIB"mstr_standard"
BODY_TYPE"PLUMBING"
HDL_TAP"TRUE";
"B \NAC \NWC"8;
"S \NAC"
BN"0"40;
%"TAP"
"1","(-5775,3350)","2","mstr_standard","I296";
;
CDS_LIB"mstr_standard"
BODY_TYPE"PLUMBING"
HDL_TAP"TRUE";
"B \NAC \NWC"8;
"S \NAC"
BN"1"38;
%"TAP"
"1","(-5775,3300)","2","mstr_standard","I297";
;
CDS_LIB"mstr_standard"
BODY_TYPE"PLUMBING"
HDL_TAP"TRUE";
"B \NAC \NWC"8;
"S \NAC"
BN"2"35;
%"TAP"
"1","(-5775,3250)","2","mstr_standard","I298";
;
CDS_LIB"mstr_standard"
BODY_TYPE"PLUMBING"
HDL_TAP"TRUE";
"B \NAC \NWC"8;
"S \NAC"
BN"3"32;
%"TAP"
"1","(-5775,3200)","2","mstr_standard","I299";
;
CDS_LIB"mstr_standard"
BODY_TYPE"PLUMBING"
HDL_TAP"TRUE";
"B \NAC \NWC"8;
"S \NAC"
BN"4"30;
%"TAP"
"1","(-5775,3100)","2","mstr_standard","I300";
;
CDS_LIB"mstr_standard"
BODY_TYPE"PLUMBING"
HDL_TAP"TRUE";
"B \NAC \NWC"8;
"S \NAC"
BN"6"26;
%"TAP"
"1","(-5775,3150)","2","mstr_standard","I301";
;
CDS_LIB"mstr_standard"
BODY_TYPE"PLUMBING"
HDL_TAP"TRUE";
"B \NAC \NWC"8;
"S \NAC"
BN"5"28;
%"Q_RES"
"1","(-6700,2100)","0","pure_quanta","I314";
;
LOCATION"R385"
$SEC"1"
CDS_SEC"1"
TOLERANCE"1%"
VALUE"15   "
PART_NUMBER"CS01502FB11"
PACK_TYPE"0402LF"
CDS_LIB"pure_quanta"
WATTAGE"1/16W"
MATERIAL"CHIP";
"B"
$PN"2"13;
"A"
$PN"1"11;
END.
